FILE_TYPE = CONNECTIVITY;
{Allegro Design Entry HDL 17.4-2019 S026 (4007227) 1/17/2022}
"PAGE_NUMBER" = 155;
0"NC";
1"P3V3_AUX\g";
2"GND\g";
3"P3V3_AUX\g";
4"GND\g";
5"GND\g";
6"GND\g";
7"GND\g";
8"P5V_AUX\g";
9"P3V3_AUX\g";
10"GND\g";
11"GND\g";
12"P1V2_CPU0_USB2_DVDD12\g";
13"P1V2_CPU0_USB2_DVDD12\g";
14"P3V3_AUX\g";
15"P1V2_CPU0_USB2_DVDD12\g";
16"P3V3_AUX_CPU0_USB2_AVDD33\g";
17"P1V2_CPU0_USB2_DVDD12\g";
18"P3V3_AUX\g";
19"P3V3_AUX\g";
20"GND\g";
21"P3V3_AUX\g";
22"P3V3_AUX\g";
23"P3V3_AUX\g";
24"GND\g";
25"P3V3_AUX\g";
26"P3V3_AUX\g";
27"GND\g";
28"GND\g";
29"GND\g";
30"GND\g";
31"GND\g";
32"P3V3_AUX\g";
33"USB_HUB2_TI_USB_VBUS_MRP_RESET_N"$PNN"USB_HUB2_TI_USB_VBUS_MRP_RESET_";
34"USB_HUB2_TI_USB_SSRXM_DN4_MRP_VDD12";
35"USB_HUB2_TI_USB_R1_MRP_RBIAS";
36"P3V3_AUX\g";
37"P1V2_CPU0_USB2_DVDD12\g";
38"P3V3_AUX_CPU0_USB2_AVDD33\g";
39"USB_HUB2_TI_USB_SSRXM_DN3_MRP_VDD12";
40"USB_HUB2_TI_USB_DM_DN3_MRP_VDD33";
41"USB_HUB2_TI_USB_DP_DN3_MRP_VDD12";
42"USB3_CPU0_BMC_RX_C2_DN";
43"USB3_CPU0_BMC_RX_C2_DP";
44"USB2_CPU0_P0_HUB2_R_DN";
45"USB2_CPU0_P0_HUB2_R_DP";
46"USB_HUB2_MRP_CFG_STRAP";
47"USB_HUB2_TI_USB_SSRXP_DN1_MRP_VDD12";
48"USB_HUB2_TI_USB_DP_DN1_MRP_CFG_STRAP";
49"USB_HUB2_TI_NC_MRP_ATEST";
50"USB_HUB2_TI_TEST_MRP_PROG_FUNC6";
51"USB_HUB2_TI_TEST";
52"USB_HUB2_MRP_PROG_FUNC6";
53"USB_HUB2_MRP_I2C_SLV_CFG1";
54"USB_HUB2_TI_OVERCUR3";
55"USB_HUB2_TI_OVERCUR2_MRP_PROG_FUNC5"$PNN"USB_HUB2_TI_OVERCUR2_MRP_PROG_F";
56"SMB_USB_CPU0_HUB1_SDA";
57"USB_HUB2_TI_OVERCUR4_MRP_I2C_SLV_CFG1";
58"USB_HUB2_TI_OVERCCUR4";
59"USB_HUB2_TI_NC_MRP_ATEST";
60"USB_HUB2_MRP_CFG_BC_EN";
61"USB_HUB2_TI_OVERCUR3_MRP_CFG_BC_EN"$PNN"USB_HUB2_TI_OVERCUR3_MRP_CFG_BC";
62"SMB_USB_CPU0_HUB1_SCL";
63"USB_HUB2_TI_OVERCUR1_MRP_PROG_FUNC4"$PNN"USB_HUB2_TI_OVERCUR1_MRP_PROG_F";
64"USB_HUB2_TI_OVERCUR2";
65"USB_HUB2_TI_OVERCUR1";
66"USB_HUB2_TI_GRSTZ_MRP_PROG_FUNC1"$PNN"USB_HUB2_TI_GRSTZ_MRP_PROG_FUNC";
67"RST_USB_HUB_N";
68"USB_HUB2_TI_PWRCTL3_MRP_VDD33";
69"USB_HUB2_TI_PWRCTL2_MRP_VDD12";
70"USB_HUB2_TI_PWRCTL_POL_MRP_VBUS_DET"$PNN"USB_HUB2_TI_PWRCTL_POL_MRP_VBUS";
71"USB3_CPU0_BMC_TX_C2_DN";
72"USB_HUB2_MRP_VBUS_DET";
73"USB_HUB2_TI_PWRCTL_POL";
74"USB_HUB2_TI_USB_VBUS";
75"USB3_CPU0_BMC_RX_HUB2_DN";
76"USB3_CPU0_BMC_RX_HUB2_DP";
77"USB2_CPU0_P0_R2_DN";
78"USB2_CPU0_P0_R2_DP";
79"USB_HUB2_MRP_RESET_N";
80"RST_USB_HUB_N";
81"USB3_CPU0_BMC_HUB2_TX_DN";
82"USB3_CPU0_BMC_HUB2_TX_DP";
83"USB3_CPU0_BMC_TX_C2_DP";
%"TUSB8042AIRGCR"
"1","(-4850,3400)","0","pure_quanta","I101";
;
LOCATION"U6002"
SEC"1"
MATERIAL"IC"
ROOM"USB3_HUB2"
VALUE"TUSB8042AIRGCR"
PART_TYPE"SMLF"
NEEDS_NO_SIZE"TRUE"
CDS_LMAN_SYM_OUTLINE"-625,2250,625,-2250"
CDS_LIB"pure_quanta"
SEC_TYPE""
PART_NUMBER"AL008042000";
"NC_1"
$PN"60"49;
"USB_R1"
$PN"64"35;
"TEST"
$PN"49"50;
"OVERCUR4Z"
$PN"43"57;
"OVERCUR3Z"
$PN"44"61;
"OVERCUR2Z"
$PN"47"55;
"OVERCUR1Z"
$PN"46"63;
"GRSTZ"
$PN"50"66;
"PWRCTL_POL"
$PN"41"70;
"PWRCTL4||BATEN4"
$PN"32"0;
"PWRCTL3||BATEN3"
$PN"33"68;
"PWRCTL2||BATEN2"
$PN"35"69;
"PWRCTL1||BATEN1"
$PN"36"0;
"USB_VBUS"
$PN"48"33;
"USB_SSTXM_DN4"
$PN"27"0;
"USB_SSTXP_DN3"
$PN"19"0;
"USB_DM_DN2"
$PN"10"44;
"USB_SSTXM_DN1"
$PN"4"0;
"USB_SSTXP_DN1"
$PN"3"0;
"USB_SSRXM_DN1"
$PN"7"0;
"USB_DP_DN1"
$PN"1"48;
"USB_SSTXM_UP"
$PN"56"75;
"USB_DP_UP"
$PN"53"78;
"TH_VSS"
$PN"TH"30;
"USB_SSRXP_DN3"
$PN"22"0;
"USB_SSRXM_DN4"
$PN"30"34;
"USB_SSRXP_DN4"
$PN"29"0;
"USB_DM_DN4"
$PN"25"0;
"USB_DM_DN1"
$PN"2"0;
"USB_SSTXP_DN4"
$PN"26"0;
"USB_SSRXP_DN1"
$PN"6"47;
"USB_DP_DN2"
$PN"9"45;
"USB_SSRXP_UP"
$PN"58"83;
"USB_DP_DN3"
$PN"17"41;
"USB_DP_DN4"
$PN"24"0;
"USB_SSRXM_DN3"
$PN"23"39;
"USB_DM_UP"
$PN"54"77;
"USB_SSTXP_UP"
$PN"55"76;
"USB_SSTXM_DN3"
$PN"20"0;
"USB_DM_DN3"
$PN"18"40;
"USB_SSTXM_DN2"
$PN"12"81;
"USB_SSTXP_DN2"
$PN"11"82;
"USB_SSRXP_DN2"
$PN"14"43;
"USB_SSRXM_DN2"
$PN"15"42;
"USB_SSRXM_UP"
$PN"59"71;
%"Q_RES"
"1","(-2375,5350)","0","pure_quanta","I102";
;
LOCATION"R6271"
$SEC"1"
CDS_SEC"1"
GROUP"HUB_MRP"
TOLERANCE"5%"
VALUE"0"
PACK_TYPE"0402LF"
MATERIAL"CHIP"
ROOM"USB3_HUB2_MRP"
WATTAGE"1/16W"
BOM_COST"VR_SYSTEM "
CDS_LIB"pure_quanta"
PART_NUMBER"CS00002JB13";
"B"
$PN"2"46;
"A"
$PN"1"48;
%"UNIVERSAL_POWER"
"1","(-1000,5900)","0","pure_quanta_power","I103";
;
HDL_POWER"P3V3_AUX"
BOM_COST"VR_SYSTEM"
CDS_LIB"pure_quanta_power";
"A"1;
%"Q_RES"
"2","(-1000,5650)","0","pure_quanta","I104";
;
LOCATION"R6273"
$SEC"1"
CDS_SEC"1"
GROUP"HUB_MRP"
ROOM"USB3_HUB2_MRP"
WATTAGE"1/16W"
TOLERANCE"1%"
MATERIAL"EMPTY"
VALUE"200K"
PACK_TYPE"0402LF"
CDS_LIB"pure_quanta"
PART_NUMBER"CS42002FB05";
"A"
$PN"1"1;
"B"
$PN"2"46;
%"Q_RES"
"2","(-1000,5100)","0","pure_quanta","I105";
;
LOCATION"R6272"
$SEC"1"
CDS_SEC"1"
GROUP"HUB_MRP"
MATERIAL"CHIP"
TOLERANCE"1%"
WATTAGE"1/16W"
VALUE"200K"
PACK_TYPE"0402LF"
ROOM"USB3_HUB2_MRP"
CDS_LIB"pure_quanta"
PART_NUMBER"CS42002FB05";
"A"
$PN"1"46;
"B"
$PN"2"2;
%"GND"
"1","(-1000,4875)","0","pure_quanta_power","I106";
;
SIZE"1B"
CDS_LIB"pure_quanta_power"
HDL_POWER"GND";
"A<SIZE-1..0>\NAC"2;
%"UNIVERSAL_POWER"
"1","(-8175,4025)","0","pure_quanta_power","I108";
;
HDL_POWER"P3V3_AUX"
BOM_COST"VR_SYSTEM"
CDS_LIB"pure_quanta_power";
"A"3;
%"GND"
"1","(-8175,3175)","0","pure_quanta_power","I110";
;
SIZE"1B"
CDS_LIB"pure_quanta_power"
HDL_POWER"GND";
"A<SIZE-1..0>\NAC"4;
%"Q_RES"
"2","(-7575,3450)","2","pure_quanta","I111";
;
LOCATION"R6333"
$SEC"1"
CDS_SEC"1"
GROUP"HUB_TI"
PACK_TYPE"0402LF"
TOLERANCE"0.1%"
WATTAGE"1/16W"
MATERIAL"EMPTY"
VALUE"47K"
ROOM"USB3_HUB2_TI"
CDS_LIB"pure_quanta"
PART_NUMBER"CS34702BB05";
"A"
$PN"1"66;
"B"
$PN"2"5;
%"GND"
"1","(-7575,3275)","0","pure_quanta_power","I112";
;
CDS_LIB"pure_quanta_power"
SIZE"1B"
HDL_POWER"GND";
"A<SIZE-1..0>\NAC"5;
%"Q_RES"
"1","(-8350,3600)","0","pure_quanta","I114";
;
LOCATION"R6328"
$SEC"1"
CDS_SEC"1"
GROUP"HUB_TI"
ROOM"USB3_HUB2_TI"
VALUE"0"
TOLERANCE"5%"
MATERIAL"CHIP"
PACK_TYPE"0402LF"
CDS_LIB"pure_quanta"
BOM_COST"VR_SYSTEM "
WATTAGE"1/16W"
PART_NUMBER"CS00002JB13";
"B"
$PN"2"66;
"A"
$PN"1"67;
%"Q_RES"
"1","(-6825,975)","0","pure_quanta","I115";
;
LOCATION"R6323"
$SEC"1"
CDS_SEC"1"
GROUP"HUB_TI"
VALUE"0"
TOLERANCE"5%"
MATERIAL"CHIP"
PACK_TYPE"0402LF"
ROOM"USB3_HUB2_TI"
BOM_COST"VR_SYSTEM "
WATTAGE"1/16W"
CDS_LIB"pure_quanta"
PART_NUMBER"CS00002JB13";
"B"
$PN"2"50;
"A"
$PN"1"51;
%"Q_RES"
"2","(-7925,775)","2","pure_quanta","I116";
;
LOCATION"R6325"
$SEC"1"
CDS_SEC"1"
GROUP"HUB_TI"
WATTAGE"1/16W"
PACK_TYPE"0402LF"
MATERIAL"CHIP"
TOLERANCE"1%"
VALUE"10K"
ROOM"USB3_HUB2_TI"
CDS_LIB"pure_quanta"
PART_NUMBER"CS31002FB08";
"A"
$PN"1"51;
"B"
$PN"2"6;
%"GND"
"1","(-7925,375)","0","pure_quanta_power","I117";
;
CDS_LIB"pure_quanta_power"
SIZE"1B"
HDL_POWER"GND";
"A<SIZE-1..0>\NAC"6;
%"Q_RES"
"1","(-6875,1300)","0","pure_quanta","I118";
;
LOCATION"R6324"
$SEC"1"
CDS_SEC"1"
GROUP"HUB_MRP"
VALUE"0"
TOLERANCE"5%"
MATERIAL"CHIP"
PACK_TYPE"0402LF"
ROOM"USB3_HUB2_MRP"
CDS_LIB"pure_quanta"
BOM_COST"VR_SYSTEM "
WATTAGE"1/16W"
PART_NUMBER"CS00002JB13";
"B"
$PN"2"50;
"A"
$PN"1"52;
%"Q_RES"
"1","(-6975,5550)","0","pure_quanta","I119";
;
LOCATION"R6316"
$SEC"1"
CDS_SEC"1"
GROUP"HUB_TI"
VALUE"0"
TOLERANCE"5%"
MATERIAL"CHIP"
PACK_TYPE"0402LF"
ROOM"USB3_HUB2_TI"
WATTAGE"1/16W"
BOM_COST"VR_SYSTEM "
CDS_LIB"pure_quanta"
PART_NUMBER"CS00002JB13";
"B"
$PN"2"33;
"A"
$PN"1"74;
%"GND"
"1","(-9100,5175)","0","pure_quanta_power","I120";
;
CDS_LIB"pure_quanta_power"
SIZE"1B"
HDL_POWER"GND";
"A<SIZE-1..0>\NAC"7;
%"Q_RES"
"2","(-9100,5400)","2","pure_quanta","I121";
;
LOCATION"R6319"
$SEC"1"
CDS_SEC"1"
GROUP"HUB_TI"
ROOM"USB3_HUB2_TI"
PACK_TYPE"0402LF"
VALUE"10K"
MATERIAL"CHIP"
WATTAGE"1/16W"
TOLERANCE"1%"
CDS_LIB"pure_quanta"
PART_NUMBER"CS31002FB08";
"A"
$PN"1"74;
"B"
$PN"2"7;
%"P1V0_AUX"
"1","(-9100,6025)","0","pure_quanta_power","I122";
;
HDL_POWER"P5V_AUX"
CDS_LIB"pure_quanta_power"
BOM_COST"VR_SYSTEM ";
"A"8;
%"Q_RES"
"2","(-9100,5750)","2","pure_quanta","I123";
;
LOCATION"R6318"
$SEC"1"
CDS_SEC"1"
GROUP"HUB_TI"
PACK_TYPE"0402LF"
ROOM"USB3_HUB2_TI"
TOLERANCE"1%"
MATERIAL"CHIP"
WATTAGE"1/16W"
VALUE"90.9K"
CDS_LIB"pure_quanta"
PART_NUMBER"CS39092FB04";
"A"
$PN"1"8;
"B"
$PN"2"74;
%"Q_RES"
"1","(-6975,6025)","0","pure_quanta","I124";
;
LOCATION"R6317"
$SEC"1"
CDS_SEC"1"
GROUP"HUB_MRP"
PACK_TYPE"0402LF"
ROOM"USB3_HUB2_MRP"
VALUE"0"
TOLERANCE"5%"
MATERIAL"CHIP"
CDS_LIB"pure_quanta"
BOM_COST"VR_SYSTEM "
WATTAGE"1/16W"
PART_NUMBER"CS00002JB13";
"B"
$PN"2"33;
"A"
$PN"1"79;
%"UNIVERSAL_POWER"
"1","(-8025,6550)","0","pure_quanta_power","I126";
;
HDL_POWER"P3V3_AUX"
CDS_LIB"pure_quanta_power"
BOM_COST"VR_SYSTEM";
"A"9;
%"Q_CAP"
"1","(-8025,5875)","0","pure_quanta","I127";
;
LOCATION"C6088"
$SEC"1"
CDS_SEC"1"
GROUP"HUB_MRP"
ROOM"USB3_HUB2_MRP"
PACK_TYPE"C0805"
VOLTAGE"16V"
VALUE"10UF"
TOLERANCE"10%"
MATERIAL"X6S"
CDS_LIB"pure_quanta"
BOM_COST"VR_SYSTEM "
PART_NUMBER"CH6103KEA00";
"B"
$PN"2"10;
"A"
$PN"1"79;
%"GND"
"1","(-8025,5650)","0","pure_quanta_power","I128";
;
SIZE"1B"
CDS_LIB"pure_quanta_power"
HDL_POWER"GND";
"A<SIZE-1..0>\NAC"10;
%"Q_RES"
"2","(-8350,5900)","0","pure_quanta","I129";
;
LOCATION"R6321"
$SEC"1"
CDS_SEC"1"
GROUP"HUB_MRP"
TOLERANCE"0.1%"
MATERIAL"EMPTY"
PACK_TYPE"0402LF"
VALUE"47K"
ROOM"USB3_HUB2_MRP"
CDS_LIB"pure_quanta"
WATTAGE"1/16W"
PART_NUMBER"CS34702BB05";
"A"
$PN"1"79;
"B"
$PN"2"11;
%"GND"
"1","(-8350,5650)","0","pure_quanta_power","I130";
;
CDS_LIB"pure_quanta_power"
SIZE"1B"
HDL_POWER"GND";
"A<SIZE-1..0>\NAC"11;
%"Q_RES"
"1","(-8600,6275)","0","pure_quanta","I131";
;
LOCATION"R6322"
$SEC"1"
CDS_SEC"1"
GROUP"HUB_MRP"
ROOM"USB3_HUB2_MRP"
MATERIAL"CHIP"
VALUE"0"
TOLERANCE"5%"
WATTAGE"1/16W"
BOM_COST"VR_SYSTEM "
CDS_LIB"pure_quanta"
PACK_TYPE"0402LF"
PART_NUMBER"CS00002JB13";
"B"
$PN"2"79;
"A"
$PN"1"80;
%"UNIVERSAL_POWER"
"1","(-1775,5250)","0","pure_quanta_power","I133";
;
HDL_POWER"P1V2_CPU0_USB2_DVDD12"
BOM_COST"VR_SYSTEM"
CDS_LIB"pure_quanta_power";
"A"12;
%"Q_RES"
"1","(-2500,5150)","0","pure_quanta","I134";
;
LOCATION"R6261"
$SEC"1"
CDS_SEC"1"
GROUP"HUB_MRP"
TOLERANCE"5%"
VALUE"0"
MATERIAL"CHIP"
ROOM"USB3_HUB2_MRP"
PACK_TYPE"0402LF"
BOM_COST"VR_SYSTEM "
WATTAGE"1/16W"
CDS_LIB"pure_quanta"
PART_NUMBER"CS00002JB13";
"B"
$PN"2"12;
"A"
$PN"1"47;
%"UNIVERSAL_POWER"
"1","(-1300,3100)","0","pure_quanta_power","I135";
;
HDL_POWER"P1V2_CPU0_USB2_DVDD12"
CDS_LIB"pure_quanta_power"
BOM_COST"VR_SYSTEM";
"A"13;
%"Q_RES"
"1","(-2450,3000)","0","pure_quanta","I136";
;
LOCATION"R6266"
$SEC"1"
CDS_SEC"1"
GROUP"HUB_MRP"
ROOM"USB3_HUB2_MRP"
TOLERANCE"5%"
PACK_TYPE"0402LF"
MATERIAL"CHIP"
VALUE"0"
WATTAGE"1/16W"
BOM_COST"VR_SYSTEM "
CDS_LIB"pure_quanta"
PART_NUMBER"CS00002JB13";
"B"
$PN"2"13;
"A"
$PN"1"39;
%"Q_RES"
"1","(-7550,2525)","0","pure_quanta","I137";
;
LOCATION"R6314"
$SEC"1"
CDS_SEC"1"
GROUP"HUB_MRP"
ROOM"USB3_HUB2_MRP"
PACK_TYPE"0402LF"
MATERIAL"CHIP"
TOLERANCE"5%"
VALUE"0"
CDS_LIB"pure_quanta"
WATTAGE"1/16W"
BOM_COST"VR_SYSTEM "
PART_NUMBER"CS00002JB13";
"B"
$PN"2"55;
"A"
$PN"1"62;
%"Q_RES"
"1","(-7575,2600)","0","pure_quanta","I138";
;
LOCATION"R6313"
$SEC"1"
CDS_SEC"1"
GROUP"HUB_TI"
ROOM"USB3_HUB2_TI"
VALUE"0"
PACK_TYPE"0402LF"
TOLERANCE"5%"
MATERIAL"CHIP"
BOM_COST"VR_SYSTEM "
WATTAGE"1/16W"
CDS_LIB"pure_quanta"
PART_NUMBER"CS00002JB13";
"B"
$PN"2"55;
"A"
$PN"1"64;
%"UNIVERSAL_POWER"
"1","(-8750,3350)","0","pure_quanta_power","I139";
;
HDL_POWER"P3V3_AUX"
BOM_COST"VR_SYSTEM"
CDS_LIB"pure_quanta_power";
"A"14;
%"Q_RES"
"2","(-8750,2950)","2","pure_quanta","I140";
;
LOCATION"R6315"
$SEC"1"
CDS_SEC"1"
GROUP"HUB_TI"
WATTAGE"1/16W"
MATERIAL"CHIP"
PACK_TYPE"0402LF"
ROOM"USB3_HUB2_TI"
TOLERANCE"1%"
VALUE"10K"
CDS_LIB"pure_quanta"
PART_NUMBER"CS31002FB08";
"A"
$PN"1"14;
"B"
$PN"2"64;
%"Q_RES"
"1","(-7200,3900)","0","pure_quanta","I143";
;
LOCATION"R6270"
$SEC"1"
CDS_SEC"1"
GROUP"HUB_MRP"
VALUE"0"
TOLERANCE"5%"
MATERIAL"CHIP"
PACK_TYPE"0402LF"
ROOM"USB3_HUB2_MRP"
WATTAGE"1/16W"
BOM_COST"VR_SYSTEM "
CDS_LIB"pure_quanta"
PART_NUMBER"CS00002JB13";
"B"
$PN"2"68;
"A"
$PN"1"38;
%"UNIVERSAL_POWER"
"1","(-7925,4125)","0","pure_quanta_power","I144";
;
HDL_POWER"P3V3_AUX_CPU0_USB2_AVDD33"
BOM_COST"VR_SYSTEM"
CDS_LIB"pure_quanta_power";
"A"38;
%"Q_CAP"
"1","(-8175,3425)","0","pure_quanta","I145";
;
LOCATION"C6089"
$SEC"1"
CDS_SEC"1"
GROUP"HUB_TI"
PACK_TYPE"C0402"
MATERIAL"X6S"
VOLTAGE"25V"
TOLERANCE"10%"
ROOM"USB3_HUB2_TI"
VALUE"1UF"
CDS_LIB"pure_quanta"
PART_NUMBER"CH5104KEB02";
"B"
$PN"2"4;
"A"
$PN"1"66;
%"UNIVERSAL_POWER"
"1","(-1650,2150)","0","pure_quanta_power","I148";
;
HDL_POWER"P1V2_CPU0_USB2_DVDD12"
BOM_COST"VR_SYSTEM"
CDS_LIB"pure_quanta_power";
"A"15;
%"Q_RES"
"1","(-2300,2050)","0","pure_quanta","I149";
;
LOCATION"R6268"
$SEC"1"
CDS_SEC"1"
GROUP"HUB_MRP"
PACK_TYPE"0402LF"
TOLERANCE"5%"
MATERIAL"CHIP"
VALUE"0"
ROOM"USB3_HUB2_MRP"
CDS_LIB"pure_quanta"
WATTAGE"1/16W"
BOM_COST"VR_SYSTEM "
PART_NUMBER"CS00002JB13";
"B"
$PN"2"15;
"A"
$PN"1"34;
%"UNIVERSAL_POWER"
"1","(-1300,3250)","0","pure_quanta_power","I150";
;
HDL_POWER"P3V3_AUX_CPU0_USB2_AVDD33"
BOM_COST"VR_SYSTEM"
CDS_LIB"pure_quanta_power";
"A"16;
%"Q_RES"
"1","(-2450,3200)","0","pure_quanta","I151";
;
LOCATION"R6264"
$SEC"1"
CDS_SEC"1"
GROUP"HUB_MRP"
ROOM"USB3_HUB2_MRP"
MATERIAL"CHIP"
VALUE"0"
PACK_TYPE"0402LF"
TOLERANCE"5%"
CDS_LIB"pure_quanta"
BOM_COST"VR_SYSTEM "
WATTAGE"1/16W"
PART_NUMBER"CS00002JB13";
"B"
$PN"2"16;
"A"
$PN"1"40;
%"UNIVERSAL_POWER"
"1","(-1675,3325)","0","pure_quanta_power","I154";
;
HDL_POWER"P1V2_CPU0_USB2_DVDD12"
BOM_COST"VR_SYSTEM"
CDS_LIB"pure_quanta_power";
"A"17;
%"Q_RES"
"1","(-2450,3250)","0","pure_quanta","I155";
;
LOCATION"R6263"
$SEC"1"
CDS_SEC"1"
GROUP"HUB_MRP"
PACK_TYPE"0402LF"
ROOM"USB3_HUB2_MRP"
TOLERANCE"5%"
MATERIAL"CHIP"
VALUE"0"
CDS_LIB"pure_quanta"
WATTAGE"1/16W"
BOM_COST"VR_SYSTEM "
PART_NUMBER"CS00002JB13";
"B"
$PN"2"17;
"A"
$PN"1"41;
%"UNIVERSAL_POWER"
"1","(-7575,4475)","0","pure_quanta_power","I163";
;
HDL_POWER"P1V2_CPU0_USB2_DVDD12"
CDS_LIB"pure_quanta_power"
BOM_COST"VR_SYSTEM";
"A"37;
%"Q_RES"
"1","(-7075,4275)","0","pure_quanta","I164";
;
LOCATION"R6258"
$SEC"1"
CDS_SEC"1"
GROUP"HUB_TI"
PACK_TYPE"0402LF"
WATTAGE"1/16W"
VALUE"4.7K"
ROOM"USB3_HUB2_TI"
MATERIAL"EMPTY"
TOLERANCE"5%"
CDS_LIB"pure_quanta"
PART_NUMBER"CS24702JB10";
"B"
$PN"2"69;
"A"
$PN"1"18;
%"UNIVERSAL_POWER"
"1","(-7400,4425)","0","pure_quanta_power","I165";
;
HDL_POWER"P3V3_AUX"
CDS_LIB"pure_quanta_power"
BOM_COST"VR_SYSTEM";
"A"18;
%"Q_RES"
"1","(-7050,4050)","0","pure_quanta","I166";
;
LOCATION"R6259"
$SEC"1"
CDS_SEC"1"
GROUP"HUB_MRP"
TOLERANCE"5%"
MATERIAL"CHIP"
VALUE"0"
PACK_TYPE"0402LF"
ROOM"USB3_HUB2_MRP"
WATTAGE"1/16W"
CDS_LIB"pure_quanta"
BOM_COST"VR_SYSTEM "
PART_NUMBER"CS00002JB13";
"B"
$PN"2"69;
"A"
$PN"1"37;
%"Q_RES"
"2","(-9075,2125)","0","pure_quanta","I169";
;
LOCATION"R6303"
$SEC"1"
CDS_SEC"1"
GROUP"HUB_MRP"
TOLERANCE"1%"
ROOM"USB3_HUB2_MRP"
WATTAGE"1/16W"
PACK_TYPE"0402LF"
VALUE"200K"
MATERIAL"EMPTY"
CDS_LIB"pure_quanta"
PART_NUMBER"CS42002FB05";
"A"
$PN"1"19;
"B"
$PN"2"60;
%"UNIVERSAL_POWER"
"1","(-9075,2350)","0","pure_quanta_power","I170";
;
HDL_POWER"P3V3_AUX"
BOM_COST"VR_SYSTEM"
CDS_LIB"pure_quanta_power";
"A"19;
%"Q_RES"
"2","(-9075,1650)","0","pure_quanta","I175";
;
LOCATION"R6302"
$SEC"1"
CDS_SEC"1"
GROUP"HUB_MRP"
ROOM"USB3_HUB2_MRP"
PACK_TYPE"0402LF"
MATERIAL"CHIP"
WATTAGE"1/16W"
TOLERANCE"1%"
VALUE"200K"
CDS_LIB"pure_quanta"
PART_NUMBER"CS42002FB05";
"A"
$PN"1"60;
"B"
$PN"2"20;
%"GND"
"1","(-9075,1475)","0","pure_quanta_power","I176";
;
CDS_LIB"pure_quanta_power"
SIZE"1B"
HDL_POWER"GND";
"A<SIZE-1..0>\NAC"20;
%"UNIVERSAL_POWER"
"1","(-9200,3300)","0","pure_quanta_power","I178";
;
HDL_POWER"P3V3_AUX"
CDS_LIB"pure_quanta_power"
BOM_COST"VR_SYSTEM";
"A"21;
%"Q_RES"
"2","(-9200,3075)","2","pure_quanta","I179";
;
LOCATION"R6301"
$SEC"1"
CDS_SEC"1"
GROUP"HUB_TI"
WATTAGE"1/16W"
MATERIAL"CHIP"
VALUE"10K"
TOLERANCE"1%"
PACK_TYPE"0402LF"
ROOM"USB3_HUB2_TI"
CDS_LIB"pure_quanta"
PART_NUMBER"CS31002FB08";
"A"
$PN"1"21;
"B"
$PN"2"54;
%"Q_RES"
"1","(-6925,2450)","0","pure_quanta","I180";
;
LOCATION"R6299"
$SEC"1"
CDS_SEC"1"
GROUP"HUB_TI"
ROOM"USB3_HUB2_TI"
MATERIAL"CHIP"
VALUE"0"
TOLERANCE"5%"
PACK_TYPE"0402LF"
CDS_LIB"pure_quanta"
WATTAGE"1/16W"
BOM_COST"VR_SYSTEM "
PART_NUMBER"CS00002JB13";
"B"
$PN"2"61;
"A"
$PN"1"54;
%"Q_RES"
"1","(-7000,2325)","0","pure_quanta","I181";
;
LOCATION"R6300"
$SEC"1"
CDS_SEC"1"
GROUP"HUB_MRP"
ROOM"USB3_HUB2_MRP"
MATERIAL"CHIP"
PACK_TYPE"0402LF"
TOLERANCE"5%"
VALUE"0"
BOM_COST"VR_SYSTEM "
WATTAGE"1/16W"
CDS_LIB"pure_quanta"
PART_NUMBER"CS00002JB13";
"B"
$PN"2"61;
"A"
$PN"1"60;
%"Q_RES"
"1","(-6500,1725)","0","pure_quanta","I182";
;
LOCATION"R6295"
$SEC"1"
CDS_SEC"1"
GROUP"HUB_TI"
VALUE"0"
TOLERANCE"5%"
ROOM"USB3_HUB2_TI"
PACK_TYPE"0402LF"
MATERIAL"CHIP"
BOM_COST"VR_SYSTEM "
WATTAGE"1/16W"
CDS_LIB"pure_quanta"
PART_NUMBER"CS00002JB13";
"B"
$PN"2"57;
"A"
$PN"1"58;
%"Q_RES"
"1","(-6475,1600)","0","pure_quanta","I183";
;
LOCATION"R6296"
$SEC"1"
CDS_SEC"1"
GROUP"HUB_MRP"
VALUE"0"
TOLERANCE"5%"
MATERIAL"CHIP"
ROOM"USB3_HUB2_MRP"
PACK_TYPE"0402LF"
CDS_LIB"pure_quanta"
BOM_COST"VR_SYSTEM "
WATTAGE"1/16W"
PART_NUMBER"CS00002JB13";
"B"
$PN"2"57;
"A"
$PN"1"53;
%"UNIVERSAL_POWER"
"1","(-7575,2175)","0","pure_quanta_power","I184";
;
HDL_POWER"P3V3_AUX"
BOM_COST"VR_SYSTEM"
CDS_LIB"pure_quanta_power";
"A"22;
%"Q_RES"
"2","(-7575,1925)","2","pure_quanta","I185";
;
LOCATION"R6297"
$SEC"1"
CDS_SEC"1"
GROUP"HUB_TI"
PACK_TYPE"0402LF"
MATERIAL"CHIP"
TOLERANCE"1%"
VALUE"10K"
ROOM"USB3_HUB2_TI"
WATTAGE"1/16W"
CDS_LIB"pure_quanta"
PART_NUMBER"CS31002FB08";
"A"
$PN"1"22;
"B"
$PN"2"58;
%"UNIVERSAL_POWER"
"1","(-8025,2175)","0","pure_quanta_power","I186";
;
HDL_POWER"P3V3_AUX"
BOM_COST"VR_SYSTEM"
CDS_LIB"pure_quanta_power";
"A"23;
%"Q_RES"
"2","(-8025,1925)","0","pure_quanta","I187";
;
LOCATION"R6298"
$SEC"1"
CDS_SEC"1"
GROUP"HUB_MRP"
ROOM"USB3_HUB2_MRP"
WATTAGE"1/16W"
MATERIAL"CHIP"
PACK_TYPE"0402LF"
TOLERANCE"1%"
VALUE"10K"
CDS_LIB"pure_quanta"
PART_NUMBER"CS31002FB08";
"A"
$PN"1"23;
"B"
$PN"2"53;
%"Q_RES"
"1","(-6200,800)","0","pure_quanta","I188";
;
LOCATION"R6330"
$SEC"1"
CDS_SEC"1"
GROUP"HUB_MRP"
TOLERANCE"1%"
PACK_TYPE"0402LF"
MATERIAL"CHIP"
VALUE"4.7K"
ROOM"USB3_HUB2_MRP"
CDS_LIB"pure_quanta"
WATTAGE"1/16W"
PART_NUMBER"CS24702FB06";
"B"
$PN"2"59;
"A"
$PN"1"24;
%"GND"
"1","(-6500,550)","0","pure_quanta_power","I189";
;
SIZE"1B"
CDS_LIB"pure_quanta_power"
HDL_POWER"GND";
"A<SIZE-1..0>\NAC"24;
%"Q_RES"
"1","(-7850,5100)","0","pure_quanta","I192";
;
LOCATION"R6285"
$SEC"1"
CDS_SEC"1"
GROUP"HUB_TI"
TOLERANCE"5%"
PACK_TYPE"0402LF"
MATERIAL"CHIP"
VALUE"0"
ROOM"USB3_HUB2_TI"
CDS_LIB"pure_quanta"
WATTAGE"1/16W"
BOM_COST"VR_SYSTEM "
PART_NUMBER"CS00002JB13";
"B"
$PN"2"70;
"A"
$PN"1"73;
%"Q_RES"
"1","(-7825,4625)","0","pure_quanta","I193";
;
LOCATION"R6286"
$SEC"1"
CDS_SEC"1"
GROUP"HUB_MRP"
MATERIAL"CHIP"
VALUE"0"
TOLERANCE"5%"
ROOM"USB3_HUB2_MRP"
PACK_TYPE"0402LF"
CDS_LIB"pure_quanta"
WATTAGE"1/16W"
BOM_COST"VR_SYSTEM "
PART_NUMBER"CS00002JB13";
"B"
$PN"2"70;
"A"
$PN"1"72;
%"UNIVERSAL_POWER"
"1","(-9175,5050)","0","pure_quanta_power","I194";
;
HDL_POWER"P3V3_AUX"
CDS_LIB"pure_quanta_power"
BOM_COST"VR_SYSTEM";
"A"25;
%"Q_RES"
"2","(-9175,4850)","2","pure_quanta","I195";
;
LOCATION"R6289"
$SEC"1"
CDS_SEC"1"
GROUP"HUB_MRP"
WATTAGE"1/16W"
PACK_TYPE"0402LF"
VALUE"10K"
TOLERANCE"1%"
MATERIAL"CHIP"
ROOM"USB3_HUB2_MRP"
CDS_LIB"pure_quanta"
PART_NUMBER"CS31002FB08";
"A"
$PN"1"25;
"B"
$PN"2"72;
%"UNIVERSAL_POWER"
"1","(-8675,5450)","0","pure_quanta_power","I196";
;
HDL_POWER"P3V3_AUX"
BOM_COST"VR_SYSTEM"
CDS_LIB"pure_quanta_power";
"A"26;
%"Q_RES"
"2","(-8675,5250)","0","pure_quanta","I197";
;
LOCATION"R6287"
$SEC"1"
CDS_SEC"1"
GROUP"HUB_TI"
PACK_TYPE"0402LF"
MATERIAL"CHIP"
TOLERANCE"1%"
WATTAGE"1/16W"
VALUE"1K"
ROOM"USB3_HUB2_TI"
CDS_LIB"pure_quanta"
PART_NUMBER"CS21002FB06";
"A"
$PN"1"26;
"B"
$PN"2"73;
%"Q_RES"
"2","(-8675,4975)","0","pure_quanta","I198";
;
LOCATION"R6288"
$SEC"1"
CDS_SEC"1"
GROUP"HUB_TI"
MATERIAL"EMPTY"
WATTAGE"1/16W"
ROOM"USB3_HUB2_TI"
TOLERANCE"1%"
PACK_TYPE"0402LF"
VALUE"1K"
CDS_LIB"pure_quanta"
PART_NUMBER"CS21002FB06";
"A"
$PN"1"73;
"B"
$PN"2"27;
%"GND"
"1","(-8675,4775)","0","pure_quanta_power","I199";
;
SIZE"1B"
CDS_LIB"pure_quanta_power"
HDL_POWER"GND";
"A<SIZE-1..0>\NAC"27;
%"Q_RES"
"1","(-6925,2750)","0","pure_quanta","I200";
;
LOCATION"R6311"
$SEC"1"
CDS_SEC"1"
GROUP"HUB_MRP"
PACK_TYPE"0402LF"
ROOM"USB3_HUB2_MRP"
VALUE"0"
TOLERANCE"5%"
MATERIAL"CHIP"
CDS_LIB"pure_quanta"
BOM_COST"VR_SYSTEM "
WATTAGE"1/16W"
PART_NUMBER"CS00002JB13";
"B"
$PN"2"63;
"A"
$PN"1"56;
%"Q_RES"
"1","(-6900,2950)","0","pure_quanta","I202";
;
LOCATION"R6310"
$SEC"1"
CDS_SEC"1"
GROUP"HUB_TI"
ROOM"USB3_HUB2_TI"
VALUE"0"
MATERIAL"CHIP"
TOLERANCE"5%"
PACK_TYPE"0402LF"
CDS_LIB"pure_quanta"
WATTAGE"1/16W"
BOM_COST"VR_SYSTEM "
PART_NUMBER"CS00002JB13";
"B"
$PN"2"63;
"A"
$PN"1"65;
%"UNIVERSAL_POWER"
"1","(-8450,3125)","0","pure_quanta_power","I204";
;
HDL_POWER"P3V3_AUX"
CDS_LIB"pure_quanta_power"
BOM_COST"VR_SYSTEM";
"A"36;
%"Q_RES"
"1","(-8125,2950)","0","pure_quanta","I205";
;
LOCATION"R6312"
SEC"1"
GROUP"HUB_TI"
MATERIAL"CHIP"
VALUE"10K"
TOLERANCE"1%"
ROOM"USB3_HUB2_TI"
PACK_TYPE"0402LF"
WATTAGE"1/16W"
SEC_TYPE"0402LF"
CDS_LIB"pure_quanta"
PART_NUMBER"CS31002FB08";
"B"
$PN"2"65;
"A"
$PN"1"36;
%"Q_RES"
"2","(-2900,1275)","0","pure_quanta","I207";
;
LOCATION"R6331"
$SEC"1"
CDS_SEC"1"
GROUP"HUB_TI"
TOLERANCE"1%"
VALUE"9.53K"
MATERIAL"CHIP"
WATTAGE"1/16W"
PACK_TYPE"0402LF"
ROOM"USB3_HUB2_TI"
CDS_LIB"pure_quanta"
PART_NUMBER"CS29532FB06";
"A"
$PN"1"35;
"B"
$PN"2"28;
%"Q_RES"
"2","(-3000,1275)","2","pure_quanta","I208";
;
LOCATION"R6332"
$SEC"1"
CDS_SEC"1"
GROUP"HUB_MRP"
MATERIAL"CHIP"
PACK_TYPE"0402LF"
TOLERANCE"1%"
VALUE"12K"
WATTAGE"1/16W"
ROOM"USB3_HUB2_MRP"
CDS_LIB"pure_quanta"
PART_NUMBER"CS31202FB04";
"A"
$PN"1"35;
"B"
$PN"2"29;
%"GND"
"1","(-2900,1000)","0","pure_quanta_power","I209";
;
CDS_LIB"pure_quanta_power"
SIZE"1B"
HDL_POWER"GND";
"A<SIZE-1..0>\NAC"28;
%"GND"
"1","(-3000,1000)","0","pure_quanta_power","I210";
;
CDS_LIB"pure_quanta_power"
SIZE"1B"
HDL_POWER"GND";
"A<SIZE-1..0>\NAC"29;
%"GND"
"1","(-3675,950)","0","pure_quanta_power","I211";
;
SIZE"1B"
CDS_LIB"pure_quanta_power"
HDL_POWER"GND";
"A<SIZE-1..0>\NAC"30;
%"Q_RES"
"2","(-8025,6300)","0","pure_quanta","I212";
;
LOCATION"R6320"
$SEC"1"
CDS_SEC"1"
GROUP"HUB_MRP"
ROOM"USB3_HUB2_MRP"
MATERIAL"EMPTY"
WATTAGE"1/16W"
TOLERANCE"1%"
VALUE"10K"
PACK_TYPE"0402LF"
CDS_LIB"pure_quanta"
PART_NUMBER"CS31002FB08";
"A"
$PN"1"9;
"B"
$PN"2"79;
%"Q_RES"
"2","(-8175,3825)","0","pure_quanta","I213";
;
LOCATION"R6329"
$SEC"1"
CDS_SEC"1"
GROUP"HUB_TI"
PACK_TYPE"0402LF"
MATERIAL"EMPTY"
TOLERANCE"1%"
ROOM"USB3_HUB2_TI"
WATTAGE"1/16W"
VALUE"10K"
CDS_LIB"pure_quanta"
PART_NUMBER"CS31002FB08";
"A"
$PN"1"3;
"B"
$PN"2"66;
%"Q_RES"
"2","(-8500,1100)","0","pure_quanta","I89";
;
LOCATION"R6326"
$SEC"1"
CDS_SEC"1"
GROUP"HUB_MRP"
ROOM"USB3_HUB2_MRP"
VALUE"4.7K"
TOLERANCE"1%"
MATERIAL"CHIP"
WATTAGE"1/16W"
PACK_TYPE"0402LF"
CDS_LIB"pure_quanta"
PART_NUMBER"CS24702FB06";
"A"
$PN"1"52;
"B"
$PN"2"31;
%"GND"
"1","(-8500,875)","0","pure_quanta_power","I90";
;
CDS_LIB"pure_quanta_power"
SIZE"1B"
HDL_POWER"GND";
"A<SIZE-1..0>\NAC"31;
%"Q_RES"
"2","(-8500,1475)","0","pure_quanta","I91";
;
LOCATION"R6327"
$SEC"1"
CDS_SEC"1"
GROUP"HUB_MRP"
ROOM"USB3_HUB2_MRP"
WATTAGE"1/16W"
VALUE"4.7K"
TOLERANCE"1%"
PACK_TYPE"0402LF"
MATERIAL"EMPTY"
CDS_LIB"pure_quanta"
PART_NUMBER"CS24702FB06";
"A"
$PN"1"32;
"B"
$PN"2"52;
%"UNIVERSAL_POWER"
"1","(-8500,1925)","0","pure_quanta_power","I92";
;
HDL_POWER"P3V3_AUX"
CDS_LIB"pure_quanta_power"
BOM_COST"VR_SYSTEM";
"A"32;
END.
